# T6G (Grand Teton) — schematic netlist excerpt (pin names and nets, part order shuffled) for the footprints in the layout excerpt that follows; sources: Cadence DE-HDL packaged netlist, KiCad conversion of 04192023_DAF0TMB3IC0_F0TG_MB_C_brd_V02_OCP.brd

H76  HOLE  EMPTY  pkg TH  page 230 : \1\ = GND
R1108  Q_RES  4.7K 5% EMPTY  pkg 0201LF  page 309 : A = P1V8_CPU0_RT_1D ; B = JTAG_TEST_MODE_RT_CPU0_P3
C6588  Q_CAP_DIFFBUS  DIFF BUS_0.22UF 6.3V 20% X6S  pkg C0201  page 297 : \1\ = P5E_CPU0_P2_TX_BUF_C_DN<11> ; \2\ = P5E_CPU0_P2_TX_BUF_DN<11>
R1564  Q_RES  33 5% CHIP  pkg 0402LF  page 81 : A = FM_ROM_LS_EN ; B = ROM_LS_EN

(kicad_pcb
	(version 20260206)
	(generator "pcbnew")
	(generator_version "10.0")
	(general
		(thickness 1.6)
		(legacy_teardrops no)
	)
	(paper "A4")
	(title_block
		(title "04192023_DAF0TMB3IC0_F0TG_MB_C_brd_V02_OCP.brd")
		(comment 1 "Grand Teton / footprints 641-644 of 8354")
	)
	(layers
		(0 "F.Cu" signal "TOP")
		(4 "In1.Cu" signal "GND")
		(6 "In2.Cu" signal "IN1")
		(8 "In3.Cu" signal "GND1")
		(10 "In4.Cu" signal "IN2")
		(12 "In5.Cu" signal "GND2")
		(14 "In6.Cu" signal "IN3")
		(16 "In7.Cu" signal "GND3")
		(18 "In8.Cu" signal "VCC")
		(20 "In9.Cu" signal "VCC1")
		(22 "In10.Cu" signal "GND4")
		(24 "In11.Cu" signal "IN4")
		(26 "In12.Cu" signal "GND5")
		(28 "In13.Cu" signal "IN5")
		(30 "In14.Cu" signal "GND6")
		(32 "In15.Cu" signal "IN6")
		(34 "In16.Cu" signal "GND7")
		(2 "B.Cu" signal "BOTTOM")
		(9 "F.Adhes" user "F.Adhesive")
		(11 "B.Adhes" user "B.Adhesive")
		(13 "F.Paste" user "Package Geometry/Pastemask Top")
		(15 "B.Paste" user "Package Geometry/Pastemask Bottom")
		(5 "F.SilkS" user "Ref Des/Silkscreen Top")
		(7 "B.SilkS" user "Ref Des/Silkscreen Bottom")
		(1 "F.Mask" user "Board Geometry/Soldermask Top")
		(3 "B.Mask" user "Board Geometry/Soldermask Bottom")
		(17 "Dwgs.User" user "User.Drawings")
		(19 "Cmts.User" user "User.Comments")
		(21 "Eco1.User" user "User.Eco1")
		(23 "Eco2.User" user "User.Eco2")
		(25 "Edge.Cuts" user "Board Geometry/Outline")
		(27 "Margin" user)
		(31 "F.CrtYd" user "Package Geometry/Place Bound Top")
		(29 "B.CrtYd" user "Package Geometry/Place Bound Bottom")
		(35 "F.Fab" user "Ref Des/Assembly Top")
		(33 "B.Fab" user "Ref Des/Assembly Bottom")
	)
	(footprint ""
		(layer "F.Cu")
		(at 239.94999 -39.420038)
		(property "Reference" "H76"
			(at -0.155702 -3.208274 0)
			(unlocked yes)
			(layer "B.SilkS")
			(effects
				(font
					(size 0.7874 0.5842)
					(thickness 0.1524)
				)
				(justify left mirror)
			)
		)
		(property "Value" ""
			(at 0 0 0)
			(layer "F.Fab")
			(effects
				(font
					(size 1.27 1.27)
				)
			)
		)
		(duplicate_pad_numbers_are_jumpers no)
		(pad "1" thru_hole rect
			(at 0 0)
			(size 4.2164 5.0038)
			(drill 2.0066
				(offset 0.099822 0)
			)
			(layers "*.Cu" "*.Mask")
			(remove_unused_layers no)
			(net "GND")
			(clearance -0.8509)
			(padstack
				(mode front_inner_back)
				(layer "Inner"
					(shape circle)
					(size 4.0132 4.0132)
					(clearance -0.7493)
				)
				(layer "B.Cu"
					(shape circle)
					(size 4.0132 4.0132)
					(clearance -0.7493)
				)
			)
		)
	)
	(footprint ""
		(layer "F.Cu")
		(at 404.564342 -416.899344 -90)
		(property "Reference" "C6588"
			(at 0 0 270)
			(layer "F.SilkS")
			(hide yes)
			(effects
				(font
					(size 1.27 1.27)
				)
			)
		)
		(property "Value" ""
			(at 0 0 270)
			(layer "F.Fab")
			(effects
				(font
					(size 1.27 1.27)
				)
			)
		)
		(duplicate_pad_numbers_are_jumpers no)
		(fp_line
			(start -0.299974 0.150114)
			(end -0.299974 -0.150114)
			(stroke
				(width 0.1)
				(type default)
			)
			(layer "F.Fab")
		)
		(fp_line
			(start 0.299974 0.150114)
			(end -0.299974 0.150114)
			(stroke
				(width 0.1)
				(type default)
			)
			(layer "F.Fab")
		)
		(fp_line
			(start -0.299974 -0.150114)
			(end 0.299974 -0.150114)
			(stroke
				(width 0.1)
				(type default)
			)
			(layer "F.Fab")
		)
		(fp_line
			(start 0.299974 -0.150114)
			(end 0.299974 0.150114)
			(stroke
				(width 0.1)
				(type default)
			)
			(layer "F.Fab")
		)
		(pad "1" smd rect
			(at -0.2667 0 270)
			(size 0.3048 0.381)
			(layers "F.Cu" "F.Mask" "F.Paste")
			(net "P5E_CPU0_P2_TX_BUF_C_DN<11>")
		)
		(pad "2" smd rect
			(at 0.2667 0 270)
			(size 0.3048 0.381)
			(layers "F.Cu" "F.Mask" "F.Paste")
			(net "P5E_CPU0_P2_TX_BUF_DN<11>")
		)
	)
	(footprint ""
		(layer "F.Cu")
		(at 369.687094 -404.873206 -90)
		(property "Reference" "R1108"
			(at 0 0 270)
			(layer "F.SilkS")
			(hide yes)
			(effects
				(font
					(size 1.27 1.27)
				)
			)
		)
		(property "Value" ""
			(at 0 0 270)
			(layer "F.Fab")
			(effects
				(font
					(size 1.27 1.27)
				)
			)
		)
		(duplicate_pad_numbers_are_jumpers no)
		(fp_line
			(start -0.32512 0.175006)
			(end -0.32512 -0.175006)
			(stroke
				(width 0.1)
				(type default)
			)
			(layer "F.Fab")
		)
		(fp_line
			(start 0.32512 0.175006)
			(end -0.32512 0.175006)
			(stroke
				(width 0.1)
				(type default)
			)
			(layer "F.Fab")
		)
		(fp_line
			(start -0.32512 -0.175006)
			(end 0.32512 -0.175006)
			(stroke
				(width 0.1)
				(type default)
			)
			(layer "F.Fab")
		)
		(fp_line
			(start 0.32512 -0.175006)
			(end 0.32512 0.175006)
			(stroke
				(width 0.1)
				(type default)
			)
			(layer "F.Fab")
		)
		(pad "1" smd rect
			(at -0.2667 0 270)
			(size 0.3048 0.381)
			(layers "F.Cu" "F.Mask" "F.Paste")
			(net "P1V8_CPU0_RT_1D")
		)
		(pad "2" smd rect
			(at 0.2667 0 90)
			(size 0.3048 0.381)
			(layers "F.Cu" "F.Mask" "F.Paste")
			(net "JTAG_TEST_MODE_RT_CPU0_P3")
		)
	)
	(footprint ""
		(layer "F.Cu")
		(at 193.167 -129.377948 90)
		(property "Reference" "R1564"
			(at 0 0 90)
			(layer "F.SilkS")
			(hide yes)
			(effects
				(font
					(size 1.27 1.27)
				)
			)
		)
		(property "Value" ""
			(at 0 0 90)
			(layer "F.Fab")
			(effects
				(font
					(size 1.27 1.27)
				)
			)
		)
		(duplicate_pad_numbers_are_jumpers no)
		(fp_line
			(start 0.7874 -0.4064)
			(end 0.7874 0.4064)
			(stroke
				(width 0.1524)
				(type default)
			)
			(layer "F.SilkS")
		)
		(fp_line
			(start -0.7874 -0.4064)
			(end 0.7874 -0.4064)
			(stroke
				(width 0.1524)
				(type default)
			)
			(layer "F.SilkS")
		)
		(fp_line
			(start 0.7874 0.4064)
			(end -0.7874 0.4064)
			(stroke
				(width 0.1524)
				(type default)
			)
			(layer "F.SilkS")
		)
		(fp_line
			(start -0.7874 0.4064)
			(end -0.7874 -0.4064)
			(stroke
				(width 0.1524)
				(type default)
			)
			(layer "F.SilkS")
		)
		(fp_line
			(start -0.12065 -0.305054)
			(end -0.12065 -0.2794)
			(stroke
				(width 0.1)
				(type default)
			)
			(layer "F.Fab")
		)
		(fp_line
			(start -0.67945 -0.305054)
			(end -0.12065 -0.305054)
			(stroke
				(width 0.1)
				(type default)
			)
			(layer "F.Fab")
		)
		(fp_line
			(start 0.67945 -0.3048)
			(end 0.67945 0.3048)
			(stroke
				(width 0.1)
				(type default)
			)
			(layer "F.Fab")
		)
		(fp_line
			(start 0.12065 -0.3048)
			(end 0.67945 -0.3048)
			(stroke
				(width 0.1)
				(type default)
			)
			(layer "F.Fab")
		)
		(fp_line
			(start 0.12065 -0.2794)
			(end 0.12065 -0.3048)
			(stroke
				(width 0.1)
				(type default)
			)
			(layer "F.Fab")
		)
		(fp_line
			(start -0.12065 -0.2794)
			(end 0.12065 -0.2794)
			(stroke
				(width 0.1)
				(type default)
			)
			(layer "F.Fab")
		)
		(fp_line
			(start 0.120396 0.2794)
			(end -0.12065 0.2794)
			(stroke
				(width 0.1)
				(type default)
			)
			(layer "F.Fab")
		)
		(fp_line
			(start -0.12065 0.2794)
			(end -0.12065 0.3048)
			(stroke
				(width 0.1)
				(type default)
			)
			(layer "F.Fab")
		)
		(fp_line
			(start 0.67945 0.3048)
			(end 0.120396 0.3048)
			(stroke
				(width 0.1)
				(type default)
			)
			(layer "F.Fab")
		)
		(fp_line
			(start 0.120396 0.3048)
			(end 0.120396 0.2794)
			(stroke
				(width 0.1)
				(type default)
			)
			(layer "F.Fab")
		)
		(fp_line
			(start -0.12065 0.3048)
			(end -0.67945 0.3048)
			(stroke
				(width 0.1)
				(type default)
			)
			(layer "F.Fab")
		)
		(fp_line
			(start -0.67945 0.3048)
			(end -0.67945 -0.305054)
			(stroke
				(width 0.1)
				(type default)
			)
			(layer "F.Fab")
		)
		(pad "1" smd circle
			(at -0.40005 0 90)
			(size 0 0)
			(layers "F.Cu" "F.Mask" "F.Paste")
			(net "FM_ROM_LS_EN")
		)
		(pad "2" smd circle
			(at 0.40005 0 90)
			(size 0 0)
			(layers "F.Cu" "F.Mask" "F.Paste")
			(net "ROM_LS_EN")
		)
	)
)
